# T6G (Grand Teton) — schematic netlist excerpt (pin names and nets, part order shuffled) for the footprints in the layout excerpt that follows; sources: Cadence DE-HDL packaged netlist, KiCad conversion of 04192023_DAF0TMB3IC0_F0TG_MB_C_brd_V02_OCP.brd

PC2164  Q_CAP  0.22UF 16V 10% X7R  pkg 0402  page 141 : A = P12V_OCP_TIMER_2 ; B = GND
R6900  Q_RES  1K 1% EMPTY  pkg 0201LF  page 354 : A = P1V8_CPU1_RT_1D ; B = RT_CPU1_P3_VQPS

U255  74LVC2G07DW7  74LVC2G07DW-7 IC  pkg SOT363_0-65_2X1-25XC  page 129
  \1a\  = GPU_NVS_PWR_BRAKE_N
  GND  = GND
  \2a\  = GPU_FPGA_EROT_RST_N
  \2y\  = GPU_FPGA_EROT_RST_BUF_R_N
  VCC  = P3V3_AUX
  \1y\  = GPU_NVS_PWR_BRAKE_N_R

(kicad_pcb
	(version 20260206)
	(generator "pcbnew")
	(generator_version "10.0")
	(general
		(thickness 1.6)
		(legacy_teardrops no)
	)
	(paper "A4")
	(title_block
		(title "04192023_DAF0TMB3IC0_F0TG_MB_C_brd_V02_OCP.brd")
		(comment 1 "Grand Teton / footprints 1624-1626 of 8354")
	)
	(layers
		(0 "F.Cu" signal "TOP")
		(4 "In1.Cu" signal "GND")
		(6 "In2.Cu" signal "IN1")
		(8 "In3.Cu" signal "GND1")
		(10 "In4.Cu" signal "IN2")
		(12 "In5.Cu" signal "GND2")
		(14 "In6.Cu" signal "IN3")
		(16 "In7.Cu" signal "GND3")
		(18 "In8.Cu" signal "VCC")
		(20 "In9.Cu" signal "VCC1")
		(22 "In10.Cu" signal "GND4")
		(24 "In11.Cu" signal "IN4")
		(26 "In12.Cu" signal "GND5")
		(28 "In13.Cu" signal "IN5")
		(30 "In14.Cu" signal "GND6")
		(32 "In15.Cu" signal "IN6")
		(34 "In16.Cu" signal "GND7")
		(2 "B.Cu" signal "BOTTOM")
		(9 "F.Adhes" user "F.Adhesive")
		(11 "B.Adhes" user "B.Adhesive")
		(13 "F.Paste" user "Package Geometry/Pastemask Top")
		(15 "B.Paste" user "Package Geometry/Pastemask Bottom")
		(5 "F.SilkS" user "Ref Des/Silkscreen Top")
		(7 "B.SilkS" user "Ref Des/Silkscreen Bottom")
		(1 "F.Mask" user "Board Geometry/Soldermask Top")
		(3 "B.Mask" user "Board Geometry/Soldermask Bottom")
		(17 "Dwgs.User" user "User.Drawings")
		(19 "Cmts.User" user "User.Comments")
		(21 "Eco1.User" user "User.Eco1")
		(23 "Eco2.User" user "User.Eco2")
		(25 "Edge.Cuts" user "Board Geometry/Outline")
		(27 "Margin" user)
		(31 "F.CrtYd" user "Package Geometry/Place Bound Top")
		(29 "B.CrtYd" user "Package Geometry/Place Bound Bottom")
		(35 "F.Fab" user "Ref Des/Assembly Top")
		(33 "B.Fab" user "Ref Des/Assembly Bottom")
	)
	(footprint ""
		(layer "F.Cu")
		(at 69.036438 -31.887922 90)
		(property "Reference" "PC2164"
			(at 0 0 90)
			(layer "F.SilkS")
			(hide yes)
			(effects
				(font
					(size 1.27 1.27)
				)
			)
		)
		(property "Value" ""
			(at 0 0 90)
			(layer "F.Fab")
			(effects
				(font
					(size 1.27 1.27)
				)
			)
		)
		(duplicate_pad_numbers_are_jumpers no)
		(fp_line
			(start 0.7874 -0.4064)
			(end 0.7874 0.4064)
			(stroke
				(width 0.1524)
				(type default)
			)
			(layer "F.SilkS")
		)
		(fp_line
			(start -0.7874 -0.4064)
			(end 0.7874 -0.4064)
			(stroke
				(width 0.1524)
				(type default)
			)
			(layer "F.SilkS")
		)
		(fp_line
			(start 0.7874 0.4064)
			(end -0.7874 0.4064)
			(stroke
				(width 0.1524)
				(type default)
			)
			(layer "F.SilkS")
		)
		(fp_line
			(start -0.7874 0.4064)
			(end -0.7874 -0.4064)
			(stroke
				(width 0.1524)
				(type default)
			)
			(layer "F.SilkS")
		)
		(fp_line
			(start -0.12065 -0.305054)
			(end -0.12065 -0.2794)
			(stroke
				(width 0.1)
				(type default)
			)
			(layer "F.Fab")
		)
		(fp_line
			(start -0.67945 -0.305054)
			(end -0.12065 -0.305054)
			(stroke
				(width 0.1)
				(type default)
			)
			(layer "F.Fab")
		)
		(fp_line
			(start 0.67945 -0.3048)
			(end 0.67945 0.3048)
			(stroke
				(width 0.1)
				(type default)
			)
			(layer "F.Fab")
		)
		(fp_line
			(start 0.12065 -0.3048)
			(end 0.67945 -0.3048)
			(stroke
				(width 0.1)
				(type default)
			)
			(layer "F.Fab")
		)
		(fp_line
			(start 0.12065 -0.2794)
			(end 0.12065 -0.3048)
			(stroke
				(width 0.1)
				(type default)
			)
			(layer "F.Fab")
		)
		(fp_line
			(start -0.12065 -0.2794)
			(end 0.12065 -0.2794)
			(stroke
				(width 0.1)
				(type default)
			)
			(layer "F.Fab")
		)
		(fp_line
			(start 0.120396 0.2794)
			(end -0.12065 0.2794)
			(stroke
				(width 0.1)
				(type default)
			)
			(layer "F.Fab")
		)
		(fp_line
			(start -0.12065 0.2794)
			(end -0.12065 0.3048)
			(stroke
				(width 0.1)
				(type default)
			)
			(layer "F.Fab")
		)
		(fp_line
			(start 0.67945 0.3048)
			(end 0.120396 0.3048)
			(stroke
				(width 0.1)
				(type default)
			)
			(layer "F.Fab")
		)
		(fp_line
			(start 0.120396 0.3048)
			(end 0.120396 0.2794)
			(stroke
				(width 0.1)
				(type default)
			)
			(layer "F.Fab")
		)
		(fp_line
			(start -0.12065 0.3048)
			(end -0.67945 0.3048)
			(stroke
				(width 0.1)
				(type default)
			)
			(layer "F.Fab")
		)
		(fp_line
			(start -0.67945 0.3048)
			(end -0.67945 -0.305054)
			(stroke
				(width 0.1)
				(type default)
			)
			(layer "F.Fab")
		)
		(pad "1" smd circle
			(at -0.40005 0 90)
			(size 0 0)
			(layers "F.Cu" "F.Mask" "F.Paste")
			(net "P12V_OCP_TIMER_2")
		)
		(pad "2" smd circle
			(at 0.40005 0 90)
			(size 0 0)
			(layers "F.Cu" "F.Mask" "F.Paste")
			(net "GND")
		)
	)
	(footprint ""
		(layer "F.Cu")
		(at 133.653022 -395.6304 -90)
		(property "Reference" "R6900"
			(at 0 0 270)
			(layer "F.SilkS")
			(hide yes)
			(effects
				(font
					(size 1.27 1.27)
				)
			)
		)
		(property "Value" ""
			(at 0 0 270)
			(layer "F.Fab")
			(effects
				(font
					(size 1.27 1.27)
				)
			)
		)
		(duplicate_pad_numbers_are_jumpers no)
		(fp_line
			(start -0.32512 0.175006)
			(end -0.32512 -0.175006)
			(stroke
				(width 0.1)
				(type default)
			)
			(layer "F.Fab")
		)
		(fp_line
			(start 0.32512 0.175006)
			(end -0.32512 0.175006)
			(stroke
				(width 0.1)
				(type default)
			)
			(layer "F.Fab")
		)
		(fp_line
			(start -0.32512 -0.175006)
			(end 0.32512 -0.175006)
			(stroke
				(width 0.1)
				(type default)
			)
			(layer "F.Fab")
		)
		(fp_line
			(start 0.32512 -0.175006)
			(end 0.32512 0.175006)
			(stroke
				(width 0.1)
				(type default)
			)
			(layer "F.Fab")
		)
		(pad "1" smd rect
			(at -0.2667 0 270)
			(size 0.3048 0.381)
			(layers "F.Cu" "F.Mask" "F.Paste")
			(net "P1V8_CPU1_RT_1D")
		)
		(pad "2" smd rect
			(at 0.2667 0 90)
			(size 0.3048 0.381)
			(layers "F.Cu" "F.Mask" "F.Paste")
			(net "RT_CPU1_P3_VQPS")
		)
	)
	(footprint ""
		(layer "F.Cu")
		(at 103.886 -423.164 -90)
		(property "Reference" "U255"
			(at 1.251712 -3.660902 90)
			(unlocked yes)
			(layer "F.SilkS")
			(effects
				(font
					(size 0.7874 0.5842)
					(thickness 0.1524)
				)
				(justify left)
			)
		)
		(property "Value" ""
			(at 0 0 270)
			(layer "F.Fab")
			(effects
				(font
					(size 1.27 1.27)
				)
			)
		)
		(duplicate_pad_numbers_are_jumpers no)
		(fp_line
			(start -1.38176 1.100074)
			(end 1.38176 1.100074)
			(stroke
				(width 0.1524)
				(type default)
			)
			(layer "F.SilkS")
		)
		(fp_line
			(start 1.38176 1.100074)
			(end 1.38176 -1.100074)
			(stroke
				(width 0.1524)
				(type default)
			)
			(layer "F.SilkS")
		)
		(fp_line
			(start 0 -0.508)
			(end -0.592074 -1.100074)
			(stroke
				(width 0.1524)
				(type default)
			)
			(layer "F.SilkS")
		)
		(fp_line
			(start -1.38176 -1.100074)
			(end -1.38176 1.100074)
			(stroke
				(width 0.1524)
				(type default)
			)
			(layer "F.SilkS")
		)
		(fp_line
			(start -0.592074 -1.100074)
			(end -1.38176 -1.100074)
			(stroke
				(width 0.1524)
				(type default)
			)
			(layer "F.SilkS")
		)
		(fp_line
			(start 0.592074 -1.100074)
			(end 0 -0.508)
			(stroke
				(width 0.1524)
				(type default)
			)
			(layer "F.SilkS")
		)
		(fp_line
			(start 1.38176 -1.100074)
			(end 0.592074 -1.100074)
			(stroke
				(width 0.1524)
				(type default)
			)
			(layer "F.SilkS")
		)
		(fp_poly
			(pts
				(xy -1.9431 -0.429768) (xy -1.9431 -0.870204) (xy -1.50241 -0.649986)
			)
			(stroke
				(width 0)
				(type default)
			)
			(fill yes)
			(layer "F.SilkS")
		)
		(fp_line
			(start -0.674878 1.100074)
			(end 0.674878 1.100074)
			(stroke
				(width 0.1)
				(type default)
			)
			(layer "F.Fab")
		)
		(fp_line
			(start 0.674878 1.100074)
			(end 0.674878 -1.100074)
			(stroke
				(width 0.1)
				(type default)
			)
			(layer "F.Fab")
		)
		(fp_line
			(start -0.674878 -1.100074)
			(end -0.674878 1.100074)
			(stroke
				(width 0.1)
				(type default)
			)
			(layer "F.Fab")
		)
		(fp_line
			(start 0.674878 -1.100074)
			(end -0.674878 -1.100074)
			(stroke
				(width 0.1)
				(type default)
			)
			(layer "F.Fab")
		)
		(fp_poly
			(pts
				(xy -1.9431 -0.870204) (xy -1.50241 -0.649986) (xy -1.9431 -0.429768)
			)
			(stroke
				(width 0)
				(type default)
			)
			(fill yes)
			(layer "F.Fab")
		)
		(pad "1" smd rect
			(at -0.94996 -0.649986 180)
			(size 0.4318 0.6096)
			(layers "F.Cu" "F.Mask" "F.Paste")
			(net "GPU_NVS_PWR_BRAKE_N")
		)
		(pad "2" smd rect
			(at -0.94996 0 180)
			(size 0.4318 0.6096)
			(layers "F.Cu" "F.Mask" "F.Paste")
			(net "GND")
		)
		(pad "3" smd rect
			(at -0.94996 0.649986 180)
			(size 0.4318 0.6096)
			(layers "F.Cu" "F.Mask" "F.Paste")
			(net "GPU_FPGA_EROT_RST_N")
		)
		(pad "4" smd rect
			(at 0.94996 0.649986 180)
			(size 0.4318 0.6096)
			(layers "F.Cu" "F.Mask" "F.Paste")
			(net "GPU_FPGA_EROT_RST_BUF_R_N")
		)
		(pad "5" smd rect
			(at 0.94996 0 180)
			(size 0.4318 0.6096)
			(layers "F.Cu" "F.Mask" "F.Paste")
			(net "P3V3_AUX")
		)
		(pad "6" smd rect
			(at 0.94996 -0.649986 180)
			(size 0.4318 0.6096)
			(layers "F.Cu" "F.Mask" "F.Paste")
			(net "GPU_NVS_PWR_BRAKE_N_R")
		)
	)
)
